(kicad_pcb
	(version 20260206)
	(generator "pcbnew")
	(generator_version "10.0")
	(general
		(thickness 1.6)
		(legacy_teardrops no)
	)
	(paper "A4")
	(title_block
		(title "03242023_DA0F0TMBIJ0_F0T_Motherboard_J_brd_V01_OCP.brd")
		(comment 1 "Grand Teton / footprint 1682 of 6105 (U1), pads 1-105 of 4677")
	)
	(layers
		(0 "F.Cu" signal "TOP")
		(4 "In1.Cu" signal "GND")
		(6 "In2.Cu" signal "IN1")
		(8 "In3.Cu" signal "GND1")
		(10 "In4.Cu" signal "IN2")
		(12 "In5.Cu" signal "GND2")
		(14 "In6.Cu" signal "IN3")
		(16 "In7.Cu" signal "GND3")
		(18 "In8.Cu" signal "VCC")
		(20 "In9.Cu" signal "VCC1")
		(22 "In10.Cu" signal "GND4")
		(24 "In11.Cu" signal "IN4")
		(26 "In12.Cu" signal "GND5")
		(28 "In13.Cu" signal "IN5")
		(30 "In14.Cu" signal "GND6")
		(32 "In15.Cu" signal "IN6")
		(34 "In16.Cu" signal "GND7")
		(2 "B.Cu" signal "BOTTOM")
		(9 "F.Adhes" user "F.Adhesive")
		(11 "B.Adhes" user "B.Adhesive")
		(13 "F.Paste" user "Package Geometry/Pastemask Top")
		(15 "B.Paste" user "Package Geometry/Pastemask Bottom")
		(5 "F.SilkS" user "Ref Des/Silkscreen Top")
		(7 "B.SilkS" user "Ref Des/Silkscreen Bottom")
		(1 "F.Mask" user "Board Geometry/Soldermask Top")
		(3 "B.Mask" user "Board Geometry/Soldermask Bottom")
		(17 "Dwgs.User" user "User.Drawings")
		(19 "Cmts.User" user "User.Comments")
		(21 "Eco1.User" user "User.Eco1")
		(23 "Eco2.User" user "User.Eco2")
		(25 "Edge.Cuts" user "Board Geometry/Outline")
		(27 "Margin" user)
		(31 "F.CrtYd" user "Package Geometry/Place Bound Top")
		(29 "B.CrtYd" user "Package Geometry/Place Bound Bottom")
		(35 "F.Fab" user "Ref Des/Assembly Top")
		(33 "B.Fab" user "Ref Des/Assembly Bottom")
	)
	(footprint ""
		(layer "F.Cu")
		(at 111.93018 -251.76988 90)
		(property "Reference" "U1"
			(at -74.913236 41.548812 0)
			(unlocked yes)
			(layer "F.SilkS")
			(effects
				(font
					(size 1.6002 1.1938)
					(thickness 0.1524)
				)
				(justify left)
			)
		)
		(property "Value" ""
			(at 0 0 90)
			(layer "F.Fab")
			(effects
				(font
					(size 1.27 1.27)
				)
			)
		)
		(duplicate_pad_numbers_are_jumpers no)
		(pad "A9" smd oval
			(at -30.914086 -27.074114 135)
			(size 0.381 0.4826)
			(drill
				(offset 0 -0.0508)
			)
			(layers "F.Cu" "F.Mask" "F.Paste")
			(net "M_A_CPU1_SB_DQS_DN<3>")
		)
		(pad "A11" smd oval
			(at -29.2862 -27.074114 90)
			(size 0.381 0.4826)
			(drill
				(offset 0 -0.0508)
			)
			(layers "F.Cu" "F.Mask" "F.Paste")
			(net "GND")
		)
		(pad "A13" smd oval
			(at -27.658314 -27.074114 90)
			(size 0.381 0.4826)
			(drill
				(offset 0 -0.0508)
			)
			(layers "F.Cu" "F.Mask" "F.Paste")
			(net "GND")
		)
		(pad "A15" smd oval
			(at -26.030682 -27.074114 90)
			(size 0.381 0.4826)
			(drill
				(offset 0 -0.0508)
			)
			(layers "F.Cu" "F.Mask" "F.Paste")
			(net "M_B_CPU1_SB_DQS_DN<3>")
		)
		(pad "A17" smd oval
			(at -24.402796 -27.074114 90)
			(size 0.381 0.4826)
			(drill
				(offset 0 -0.0508)
			)
			(layers "F.Cu" "F.Mask" "F.Paste")
			(net "GND")
		)
		(pad "A19" smd oval
			(at -22.77491 -27.074114 90)
			(size 0.381 0.4826)
			(drill
				(offset 0 -0.0508)
			)
			(layers "F.Cu" "F.Mask" "F.Paste")
			(net "GND")
		)
		(pad "A21" smd oval
			(at -21.147278 -27.074114 90)
			(size 0.381 0.4826)
			(drill
				(offset 0 -0.0508)
			)
			(layers "F.Cu" "F.Mask" "F.Paste")
			(net "M_A_CPU1_SB_DQS_DN<2>")
		)
		(pad "A23" smd oval
			(at -19.519392 -27.074114 90)
			(size 0.381 0.4826)
			(drill
				(offset 0 -0.0508)
			)
			(layers "F.Cu" "F.Mask" "F.Paste")
			(net "GND")
		)
		(pad "A25" smd oval
			(at -17.89176 -27.074114 90)
			(size 0.381 0.4826)
			(drill
				(offset 0 -0.0508)
			)
			(layers "F.Cu" "F.Mask" "F.Paste")
			(net "GND")
		)
		(pad "A27" smd oval
			(at -16.263874 -27.074114 90)
			(size 0.381 0.4826)
			(drill
				(offset 0 -0.0508)
			)
			(layers "F.Cu" "F.Mask" "F.Paste")
			(net "M_A_CPU1_SB_DQS_DN<1>")
		)
		(pad "A29" smd oval
			(at -14.635988 -27.074114 90)
			(size 0.381 0.4826)
			(drill
				(offset 0 -0.0508)
			)
			(layers "F.Cu" "F.Mask" "F.Paste")
			(net "GND")
		)
		(pad "A31" smd oval
			(at -13.008356 -27.074114 90)
			(size 0.381 0.4826)
			(drill
				(offset 0 -0.0508)
			)
			(layers "F.Cu" "F.Mask" "F.Paste")
			(net "GND")
		)
		(pad "A33" smd oval
			(at -11.380724 -27.074114 90)
			(size 0.381 0.4826)
			(drill
				(offset 0 -0.0508)
			)
			(layers "F.Cu" "F.Mask" "F.Paste")
			(net "M_A_CPU1_SB_DQS_DN<9>")
		)
		(pad "A35" smd oval
			(at -9.752838 -27.074114 90)
			(size 0.381 0.4826)
			(drill
				(offset 0 -0.0508)
			)
			(layers "F.Cu" "F.Mask" "F.Paste")
			(net "GND")
		)
		(pad "A37" smd oval
			(at -8.124952 -27.074114 90)
			(size 0.381 0.4826)
			(drill
				(offset 0 -0.0508)
			)
			(layers "F.Cu" "F.Mask" "F.Paste")
			(net "GND")
		)
		(pad "A39" smd oval
			(at -6.49732 -27.074114 90)
			(size 0.381 0.4826)
			(drill
				(offset 0 -0.0508)
			)
			(layers "F.Cu" "F.Mask" "F.Paste")
			(net "M_A_CPU1_SB_CA<6>")
		)
		(pad "A41" smd oval
			(at -4.869434 -27.074114 90)
			(size 0.381 0.4826)
			(drill
				(offset 0 -0.0508)
			)
			(layers "F.Cu" "F.Mask" "F.Paste")
			(net "GND")
		)
		(pad "A43" smd oval
			(at -3.241802 -27.074114 90)
			(size 0.381 0.4826)
			(drill
				(offset 0 -0.0508)
			)
			(layers "F.Cu" "F.Mask" "F.Paste")
			(net "PWRGD_DRAMPWRGD_CPU1_AB_LVC1_R")
		)
		(pad "A50" smd oval
			(at 4.055618 -26.964132 90)
			(size 0.381 0.4826)
			(drill
				(offset 0 -0.0508)
			)
			(layers "F.Cu" "F.Mask" "F.Paste")
			(net "GND")
		)
		(pad "A52" smd oval
			(at 5.68325 -26.964132 90)
			(size 0.381 0.4826)
			(drill
				(offset 0 -0.0508)
			)
			(layers "F.Cu" "F.Mask" "F.Paste")
			(net "M_A_CPU1_SA_CA<0>")
		)
		(pad "A54" smd oval
			(at 7.311136 -26.964132 90)
			(size 0.381 0.4826)
			(drill
				(offset 0 -0.0508)
			)
			(layers "F.Cu" "F.Mask" "F.Paste")
			(net "GND")
		)
		(pad "A56" smd oval
			(at 8.939022 -26.964132 90)
			(size 0.381 0.4826)
			(drill
				(offset 0 -0.0508)
			)
			(layers "F.Cu" "F.Mask" "F.Paste")
			(net "GND")
		)
		(pad "A58" smd oval
			(at 10.566654 -26.964132 90)
			(size 0.381 0.4826)
			(drill
				(offset 0 -0.0508)
			)
			(layers "F.Cu" "F.Mask" "F.Paste")
			(net "M_A_CPU1_SA_DQS_DN<4>")
		)
		(pad "A60" smd oval
			(at 12.19454 -26.964132 90)
			(size 0.381 0.4826)
			(drill
				(offset 0 -0.0508)
			)
			(layers "F.Cu" "F.Mask" "F.Paste")
			(net "GND")
		)
		(pad "A62" smd oval
			(at 13.822426 -26.964132 90)
			(size 0.381 0.4826)
			(drill
				(offset 0 -0.0508)
			)
			(layers "F.Cu" "F.Mask" "F.Paste")
			(net "GND")
		)
		(pad "A64" smd oval
			(at 15.450058 -26.964132 90)
			(size 0.381 0.4826)
			(drill
				(offset 0 -0.0508)
			)
			(layers "F.Cu" "F.Mask" "F.Paste")
			(net "M_A_CPU1_SA_DQS_DN<3>")
		)
		(pad "AA1" smd oval
			(at -37.425122 -17.676114 180)
			(size 0.381 0.4826)
			(drill
				(offset 0 -0.0508)
			)
			(layers "F.Cu" "F.Mask" "F.Paste")
			(net "UPI_CPU1_CPU0_P0P1_DN<6>")
		)
		(pad "AA3" smd circle
			(at -35.797236 -17.676114 270)
			(size 0.4318 0.4318)
			(layers "F.Cu" "F.Mask" "F.Paste")
			(net "PVCCFA_EHV_CPU1")
		)
		(pad "AA5" smd circle
			(at -34.169604 -17.676114 270)
			(size 0.4318 0.4318)
			(layers "F.Cu" "F.Mask" "F.Paste")
			(net "UPI_CPU0_CPU1_P1P0_DN<5>")
		)
		(pad "AA7" smd circle
			(at -32.541718 -17.676114 270)
			(size 0.4318 0.4318)
			(layers "F.Cu" "F.Mask" "F.Paste")
			(net "PVCCFA_EHV_FIVRA_CPU1")
		)
		(pad "AA9" smd circle
			(at -30.914086 -17.676114 270)
			(size 0.4318 0.4318)
			(layers "F.Cu" "F.Mask" "F.Paste")
			(net "P5E_CPU1_PE0_RX_DN<5>")
		)
		(pad "AA11" smd circle
			(at -29.2862 -17.676114 270)
			(size 0.4318 0.4318)
			(layers "F.Cu" "F.Mask" "F.Paste")
			(net "PVCCFA_EHV_FIVRA_CPU1")
		)
		(pad "AA13" smd circle
			(at -27.658314 -17.676114 270)
			(size 0.4318 0.4318)
			(layers "F.Cu" "F.Mask" "F.Paste")
			(net "P5E_CPU1_PE0_TX_DN<4>")
		)
		(pad "AA15" smd circle
			(at -26.030682 -17.676114 270)
			(size 0.4318 0.4318)
			(layers "F.Cu" "F.Mask" "F.Paste")
			(net "PVCCFA_EHV_FIVRA_CPU1")
		)
		(pad "AA17" smd circle
			(at -24.402796 -17.676114 270)
			(size 0.4318 0.4318)
			(layers "F.Cu" "F.Mask" "F.Paste")
			(net "M_C_CPU1_SB_DQ<28>")
		)
		(pad "AA19" smd circle
			(at -22.77491 -17.676114 270)
			(size 0.4318 0.4318)
			(layers "F.Cu" "F.Mask" "F.Paste")
			(net "GND")
		)
		(pad "AA21" smd circle
			(at -21.147278 -17.676114 270)
			(size 0.4318 0.4318)
			(layers "F.Cu" "F.Mask" "F.Paste")
			(net "M_C_CPU1_SB_DQS_DP<7>")
		)
		(pad "AA23" smd circle
			(at -19.519392 -17.676114 270)
			(size 0.4318 0.4318)
			(layers "F.Cu" "F.Mask" "F.Paste")
			(net "GND")
		)
		(pad "AA25" smd circle
			(at -17.89176 -17.676114 270)
			(size 0.4318 0.4318)
			(layers "F.Cu" "F.Mask" "F.Paste")
			(net "GND")
		)
		(pad "AA27" smd circle
			(at -16.263874 -17.676114 270)
			(size 0.4318 0.4318)
			(layers "F.Cu" "F.Mask" "F.Paste")
			(net "M_B_CPU1_SB_DQS_DP<5>")
		)
		(pad "AA29" smd circle
			(at -14.635988 -17.676114 270)
			(size 0.4318 0.4318)
			(layers "F.Cu" "F.Mask" "F.Paste")
			(net "GND")
		)
		(pad "AA31" smd circle
			(at -13.008356 -17.676114 270)
			(size 0.4318 0.4318)
			(layers "F.Cu" "F.Mask" "F.Paste")
			(net "GND")
		)
		(pad "AA33" smd circle
			(at -11.380724 -17.676114 270)
			(size 0.4318 0.4318)
			(layers "F.Cu" "F.Mask" "F.Paste")
			(net "M_C_CPU1_SB_DQS_DP<4>")
		)
		(pad "AA35" smd circle
			(at -9.752838 -17.676114 270)
			(size 0.4318 0.4318)
			(layers "F.Cu" "F.Mask" "F.Paste")
			(net "GND")
		)
		(pad "AA37" smd circle
			(at -8.124952 -17.676114 270)
			(size 0.4318 0.4318)
			(layers "F.Cu" "F.Mask" "F.Paste")
			(net "GND")
		)
		(pad "AA39" smd circle
			(at -6.49732 -17.676114 270)
			(size 0.4318 0.4318)
			(layers "F.Cu" "F.Mask" "F.Paste")
			(net "M_C_CPU1_SB_PAR")
		)
		(pad "AA41" smd circle
			(at -4.869434 -17.676114 270)
			(size 0.4318 0.4318)
			(layers "F.Cu" "F.Mask" "F.Paste")
			(net "GND")
		)
		(pad "AA43" smd circle
			(at -3.241802 -17.676114 270)
			(size 0.4318 0.4318)
			(layers "F.Cu" "F.Mask" "F.Paste")
			(net "GND")
		)
		(pad "AA45" smd circle
			(at -1.613916 -17.676114 270)
			(size 0.4318 0.4318)
			(layers "F.Cu" "F.Mask" "F.Paste")
			(net "M_B_CPU1_CLK_DP<1>")
		)
		(pad "AA48" smd circle
			(at 2.427732 -17.566132 270)
			(size 0.4318 0.4318)
			(layers "F.Cu" "F.Mask" "F.Paste")
			(net "GND")
		)
		(pad "AA50" smd circle
			(at 4.055618 -17.566132 270)
			(size 0.4318 0.4318)
			(layers "F.Cu" "F.Mask" "F.Paste")
			(net "GND")
		)
		(pad "AA52" smd circle
			(at 5.68325 -17.566132 270)
			(size 0.4318 0.4318)
			(layers "F.Cu" "F.Mask" "F.Paste")
			(net "M_C_CPU1_SA_CA<1>")
		)
		(pad "AA54" smd circle
			(at 7.311136 -17.566132 270)
			(size 0.4318 0.4318)
			(layers "F.Cu" "F.Mask" "F.Paste")
			(net "GND")
		)
		(pad "AA56" smd circle
			(at 8.939022 -17.566132 270)
			(size 0.4318 0.4318)
			(layers "F.Cu" "F.Mask" "F.Paste")
			(net "GND")
		)
		(pad "AA58" smd circle
			(at 10.566654 -17.566132 270)
			(size 0.4318 0.4318)
			(layers "F.Cu" "F.Mask" "F.Paste")
			(net "M_B_CPU1_SA_DQS_DN<8>")
		)
		(pad "AA60" smd circle
			(at 12.19454 -17.566132 270)
			(size 0.4318 0.4318)
			(layers "F.Cu" "F.Mask" "F.Paste")
			(net "GND")
		)
		(pad "AA62" smd circle
			(at 13.822426 -17.566132 270)
			(size 0.4318 0.4318)
			(layers "F.Cu" "F.Mask" "F.Paste")
			(net "GND")
		)
		(pad "AA64" smd circle
			(at 15.450058 -17.566132 270)
			(size 0.4318 0.4318)
			(layers "F.Cu" "F.Mask" "F.Paste")
			(net "M_C_CPU1_SA_DQS_DN<7>")
		)
		(pad "AA66" smd circle
			(at 17.07769 -17.566132 270)
			(size 0.4318 0.4318)
			(layers "F.Cu" "F.Mask" "F.Paste")
			(net "GND")
		)
		(pad "AA68" smd circle
			(at 18.705576 -17.566132 270)
			(size 0.4318 0.4318)
			(layers "F.Cu" "F.Mask" "F.Paste")
			(net "GND")
		)
		(pad "AA70" smd circle
			(at 20.333462 -17.566132 270)
			(size 0.4318 0.4318)
			(layers "F.Cu" "F.Mask" "F.Paste")
			(net "M_B_CPU1_SA_DQS_DN<6>")
		)
		(pad "AA72" smd circle
			(at 21.961094 -17.566132 270)
			(size 0.4318 0.4318)
			(layers "F.Cu" "F.Mask" "F.Paste")
			(net "GND")
		)
		(pad "AA74" smd circle
			(at 23.58898 -17.566132 270)
			(size 0.4318 0.4318)
			(layers "F.Cu" "F.Mask" "F.Paste")
			(net "GND")
		)
		(pad "AA76" smd circle
			(at 25.216612 -17.566132 270)
			(size 0.4318 0.4318)
			(layers "F.Cu" "F.Mask" "F.Paste")
			(net "M_C_CPU1_SA_DQS_DP<5>")
		)
		(pad "AA78" smd circle
			(at 26.844498 -17.566132 270)
			(size 0.4318 0.4318)
			(layers "F.Cu" "F.Mask" "F.Paste")
			(net "GND")
		)
		(pad "AA80" smd circle
			(at 28.472384 -17.566132 270)
			(size 0.4318 0.4318)
			(layers "F.Cu" "F.Mask" "F.Paste")
			(net "GND")
		)
		(pad "AA82" smd circle
			(at 30.100016 -17.566132 270)
			(size 0.4318 0.4318)
			(layers "F.Cu" "F.Mask" "F.Paste")
			(net "GND")
		)
		(pad "AA84" smd circle
			(at 31.727902 -17.566132 270)
			(size 0.4318 0.4318)
			(layers "F.Cu" "F.Mask" "F.Paste")
			(net "GND")
		)
		(pad "AA86" smd circle
			(at 33.355534 -17.566132 270)
			(size 0.4318 0.4318)
			(layers "F.Cu" "F.Mask" "F.Paste")
			(net "P5E_CPU1_PE4_TX_DN<5>")
		)
		(pad "AA88" smd circle
			(at 34.98342 -17.566132 270)
			(size 0.4318 0.4318)
			(layers "F.Cu" "F.Mask" "F.Paste")
			(net "GND")
		)
		(pad "AA90" smd circle
			(at 36.611306 -17.566132 270)
			(size 0.4318 0.4318)
			(layers "F.Cu" "F.Mask" "F.Paste")
			(net "P5E_CPU1_PE4_RX_DP<5>")
		)
		(pad "AB2" smd circle
			(at -36.611306 -17.206468 270)
			(size 0.4318 0.4318)
			(layers "F.Cu" "F.Mask" "F.Paste")
			(net "UPI_CPU1_CPU0_P0P1_DP<6>")
		)
		(pad "AB4" smd circle
			(at -34.98342 -17.206468 270)
			(size 0.4318 0.4318)
			(layers "F.Cu" "F.Mask" "F.Paste")
			(net "GND")
		)
		(pad "AB6" smd circle
			(at -33.355534 -17.206468 270)
			(size 0.4318 0.4318)
			(layers "F.Cu" "F.Mask" "F.Paste")
			(net "UPI_CPU0_CPU1_P1P0_DN<6>")
		)
		(pad "AB8" smd circle
			(at -31.727902 -17.206468 270)
			(size 0.4318 0.4318)
			(layers "F.Cu" "F.Mask" "F.Paste")
			(net "GND")
		)
		(pad "AB10" smd circle
			(at -30.100016 -17.206468 270)
			(size 0.4318 0.4318)
			(layers "F.Cu" "F.Mask" "F.Paste")
			(net "P5E_CPU1_PE0_RX_DN<6>")
		)
		(pad "AB12" smd circle
			(at -28.472384 -17.206468 270)
			(size 0.4318 0.4318)
			(layers "F.Cu" "F.Mask" "F.Paste")
			(net "GND")
		)
		(pad "AB14" smd circle
			(at -26.844498 -17.206468 270)
			(size 0.4318 0.4318)
			(layers "F.Cu" "F.Mask" "F.Paste")
			(net "P5E_CPU1_PE0_TX_DN<5>")
		)
		(pad "AB16" smd circle
			(at -25.216612 -17.206468 270)
			(size 0.4318 0.4318)
			(layers "F.Cu" "F.Mask" "F.Paste")
			(net "GND")
		)
		(pad "AB18" smd circle
			(at -23.58898 -17.206468 270)
			(size 0.4318 0.4318)
			(layers "F.Cu" "F.Mask" "F.Paste")
			(net "M_C_CPU1_SB_DQS_DN<3>")
		)
		(pad "AB20" smd circle
			(at -21.961094 -17.206468 270)
			(size 0.4318 0.4318)
			(layers "F.Cu" "F.Mask" "F.Paste")
			(net "GND")
		)
		(pad "AB22" smd circle
			(at -20.333462 -17.206468 270)
			(size 0.4318 0.4318)
			(layers "F.Cu" "F.Mask" "F.Paste")
			(net "GND")
		)
		(pad "AB24" smd circle
			(at -18.705576 -17.206468 270)
			(size 0.4318 0.4318)
			(layers "F.Cu" "F.Mask" "F.Paste")
			(net "M_D_CPU1_SB_DQS_DN<2>")
		)
		(pad "AB26" smd circle
			(at -17.07769 -17.206468 270)
			(size 0.4318 0.4318)
			(layers "F.Cu" "F.Mask" "F.Paste")
			(net "GND")
		)
		(pad "AB28" smd circle
			(at -15.450058 -17.206468 270)
			(size 0.4318 0.4318)
			(layers "F.Cu" "F.Mask" "F.Paste")
			(net "GND")
		)
		(pad "AB30" smd circle
			(at -13.822426 -17.206468 270)
			(size 0.4318 0.4318)
			(layers "F.Cu" "F.Mask" "F.Paste")
			(net "M_C_CPU1_SB_DQS_DN<1>")
		)
		(pad "AB32" smd circle
			(at -12.19454 -17.206468 270)
			(size 0.4318 0.4318)
			(layers "F.Cu" "F.Mask" "F.Paste")
			(net "GND")
		)
		(pad "AB34" smd circle
			(at -10.566654 -17.206468 270)
			(size 0.4318 0.4318)
			(layers "F.Cu" "F.Mask" "F.Paste")
			(net "GND")
		)
		(pad "AB36" smd circle
			(at -8.939022 -17.206468 270)
			(size 0.4318 0.4318)
			(layers "F.Cu" "F.Mask" "F.Paste")
			(net "M_C_CPU1_SB_DQS_DN<0>")
		)
		(pad "AB38" smd circle
			(at -7.311136 -17.206468 270)
			(size 0.4318 0.4318)
			(layers "F.Cu" "F.Mask" "F.Paste")
			(net "GND")
		)
		(pad "AB40" smd circle
			(at -5.68325 -17.206468 270)
			(size 0.4318 0.4318)
			(layers "F.Cu" "F.Mask" "F.Paste")
			(net "GND")
		)
		(pad "AB42" smd circle
			(at -4.055618 -17.206468 270)
			(size 0.4318 0.4318)
			(layers "F.Cu" "F.Mask" "F.Paste")
			(net "M_D_CPU1_SB_CA<6>")
		)
		(pad "AB44" smd circle
			(at -2.427732 -17.206468 270)
			(size 0.4318 0.4318)
			(layers "F.Cu" "F.Mask" "F.Paste")
			(net "GND")
		)
		(pad "AB47" smd circle
			(at 1.613916 -17.096486 270)
			(size 0.4318 0.4318)
			(layers "F.Cu" "F.Mask" "F.Paste")
			(net "GND")
		)
		(pad "AB49" smd circle
			(at 3.241802 -17.096486 270)
			(size 0.4318 0.4318)
			(layers "F.Cu" "F.Mask" "F.Paste")
			(net "M_C_CPU1_CLK_DN<0>")
		)
		(pad "AB51" smd circle
			(at 4.869434 -17.096486 270)
			(size 0.4318 0.4318)
			(layers "F.Cu" "F.Mask" "F.Paste")
			(net "GND")
		)
		(pad "AB53" smd circle
			(at 6.49732 -17.096486 270)
			(size 0.4318 0.4318)
			(layers "F.Cu" "F.Mask" "F.Paste")
			(net "GND")
		)
		(pad "AB55" smd circle
			(at 8.124952 -17.096486 270)
			(size 0.4318 0.4318)
			(layers "F.Cu" "F.Mask" "F.Paste")
			(net "M_C_CPU1_SA_DQS_DP<4>")
		)
		(pad "AB57" smd circle
			(at 9.752838 -17.096486 270)
			(size 0.4318 0.4318)
			(layers "F.Cu" "F.Mask" "F.Paste")
			(net "GND")
		)
		(pad "AB59" smd circle
			(at 11.380724 -17.096486 270)
			(size 0.4318 0.4318)
			(layers "F.Cu" "F.Mask" "F.Paste")
			(net "GND")
		)
		(pad "AB61" smd circle
			(at 13.008356 -17.096486 270)
			(size 0.4318 0.4318)
			(layers "F.Cu" "F.Mask" "F.Paste")
			(net "M_C_CPU1_SA_DQS_DN<3>")
		)
		(pad "AB63" smd circle
			(at 14.635988 -17.096486 270)
			(size 0.4318 0.4318)
			(layers "F.Cu" "F.Mask" "F.Paste")
			(net "GND")
		)
		(pad "AB65" smd circle
			(at 16.263874 -17.096486 270)
			(size 0.4318 0.4318)
			(layers "F.Cu" "F.Mask" "F.Paste")
			(net "GND")
		)
		(pad "AB67" smd circle
			(at 17.89176 -17.096486 270)
			(size 0.4318 0.4318)
			(layers "F.Cu" "F.Mask" "F.Paste")
			(net "M_C_CPU1_SA_DQS_DN<1>")
		)
		(pad "AB69" smd circle
			(at 19.519392 -17.096486 270)
			(size 0.4318 0.4318)
			(layers "F.Cu" "F.Mask" "F.Paste")
			(net "GND")
		)
	)
)
